# S9S_MB_2U (Grand Teton) — schematic netlist excerpt (pin names and nets, part order shuffled) for the footprints in the layout excerpt that follows; sources: Cadence DE-HDL packaged netlist, KiCad conversion of 03242023_DA0F0TMBIJ0_F0T_Motherboard_J_brd_V01_OCP.brd

J6  SCONN288_ADR50017P087CC  SCONN288_ADR50017-P087CC IO  pkg DDR288S_1-1VXB  page 87
  VIN_BULK0  = P12V_S3_AUX_CPU0_NVDIMM
  RFU0  = TP_CHC_CPU0_DIMM2_FRU_0
  VIN_MGMT  = P3V3_AUX
  HSCL  = I3C_SPD_DDRABCD_CPU0_LVC1_SCL_5
  HSDA  = I3C_SPD_DDRABCD_CPU0_LVC1_SDA
  VSS0  = GND
  DQ0_A  = M_C_CPU0_SA_DQ<0>
  VSS1  = GND
  DQ1_A  = M_C_CPU0_SA_DQ<1>
  VSS2  = GND
  DQS0_A_T  = M_C_CPU0_SA_DQS_DP<0>
  DQS0_A_C  = M_C_CPU0_SA_DQS_DN<0>
  VSS3  = GND
  DQ4_A  = M_C_CPU0_SA_DQ<4>
  VSS4  = GND
  DQ5_A  = M_C_CPU0_SA_DQ<5>
  VSS5  = GND
  DQ8_A  = M_C_CPU0_SA_DQ<8>
  VSS6  = GND
  DQ9_A  = M_C_CPU0_SA_DQ<9>
  VSS7  = GND
  DQS1_A_T  = M_C_CPU0_SA_DQS_DP<1>
  DQS1_A_C  = M_C_CPU0_SA_DQS_DN<1>
  VSS8  = GND
  DQ12_A  = M_C_CPU0_SA_DQ<12>
  VSS9  = GND
  DQ13_A  = M_C_CPU0_SA_DQ<13>
  VSS10  = GND
  DQ16_A  = M_C_CPU0_SA_DQ<16>
  VSS11  = GND
  DQ17_A  = M_C_CPU0_SA_DQ<17>
  VSS12  = GND
  DQS2_A_T  = M_C_CPU0_SA_DQS_DP<2>
  DQS2_A_C  = M_C_CPU0_SA_DQS_DN<2>
  VSS13  = GND
  DQ20_A  = M_C_CPU0_SA_DQ<20>
  VSS14  = GND
  DQ21_A  = M_C_CPU0_SA_DQ<21>
  VSS15  = GND
  DQ24_A  = M_C_CPU0_SA_DQ<24>
  VSS16  = GND
  DQ25_A  = M_C_CPU0_SA_DQ<25>
  VSS17  = GND
  DQS3_A_T  = M_C_CPU0_SA_DQS_DP<3>
  DQS3_A_C  = M_C_CPU0_SA_DQS_DN<3>
  VSS18  = GND
  DQ28_A  = M_C_CPU0_SA_DQ<28>
  VSS19  = GND
  DQ29_A  = M_C_CPU0_SA_DQ<29>
  VSS20  = GND
  CB0_A  = M_C_CPU0_SA_CB<0>
  VSS21  = GND
  CB1_A  = M_C_CPU0_SA_CB<1>
  VSS22  = GND
  DQS4_A_T  = M_C_CPU0_SA_DQS_DP<4>
  DQS4_A_C  = M_C_CPU0_SA_DQS_DN<4>
  VSS23  = GND
  CB4_A  = M_C_CPU0_SA_CB<4>
  VSS24  = GND
  CB5_A  = M_C_CPU0_SA_CB<5>
  VSS25  = GND
  ALERT_N  = M_C_CPU0_ALERT_N
  VSS26  = GND
  CS0_A_N  = M_C_CPU0_SA_CS_N<2>
  VSS27  = GND
  CA0_A  = M_C_CPU0_SA_CA<0>
  VSS28  = GND
  CA2_A  = M_C_CPU0_SA_CA<2>
  VSS29  = GND
  CA4_A  = M_C_CPU0_SA_CA<4>
  VSS30  = GND
  CA6_A  = M_C_CPU0_SA_CA<6>
  VSS31  = GND
  PAR_A  = M_C_CPU0_SA_PAR
  VSS32  = GND
  CA0_B  = M_C_CPU0_SB_CA<0>
  VSS33  = GND
  CA2_B  = M_C_CPU0_SB_CA<2>
  VSS34  = GND
  CA4_B  = M_C_CPU0_SB_CA<4>
  VSS35  = GND
  CA6_B  = M_C_CPU0_SB_CA<6>
  VSS36  = GND
  CS0_B_N  = M_C_CPU0_SB_CS_N<2>
  VSS37  = GND
  \lbd||rsp_a_n\  = M_C_CPU0_SA_RSP<1>
  \lbs||rsp_b_n\  = M_C_CPU0_SB_RSP<1>
  VSS38  = GND
  CB4_B  = M_C_CPU0_SB_CB<4>
  VSS39  = GND
  CB5_B  = M_C_CPU0_SB_CB<5>
  VSS40  = GND
  \dqs9_b_t||tdqs9_b_t||dbi4_b_n\  = M_C_CPU0_SB_DQS_DP<9>
  \dqs9_b_c||tdqs9_b_c\  = M_C_CPU0_SB_DQS_DN<9>
  VSS41  = GND
  CB0_B  = M_C_CPU0_SB_CB<0>
  VSS42  = GND
  CB1_B  = M_C_CPU0_SB_CB<1>
  VSS43  = GND
  DQ0_B  = M_C_CPU0_SB_DQ<0>
  VSS44  = GND
  DQ1_B  = M_C_CPU0_SB_DQ<1>
  VSS45  = GND
  DQS0_B_T  = M_C_CPU0_SB_DQS_DP<0>
  DQS0_B_C  = M_C_CPU0_SB_DQS_DN<0>
  VSS46  = GND
  DQ4_B  = M_C_CPU0_SB_DQ<4>
  VSS47  = GND
  DQ5_B  = M_C_CPU0_SB_DQ<5>
  VSS48  = GND
  DQ8_B  = M_C_CPU0_SB_DQ<8>
  VSS49  = GND
  DQ9_B  = M_C_CPU0_SB_DQ<9>
  VSS50  = GND
  DQS1_B_T  = M_C_CPU0_SB_DQS_DP<1>
  DQS1_B_C  = M_C_CPU0_SB_DQS_DN<1>
  VSS51  = GND
  DQ12_B  = M_C_CPU0_SB_DQ<12>
  VSS52  = GND
  DQ13_B  = M_C_CPU0_SB_DQ<13>
  VSS53  = GND
  DQ16_B  = M_C_CPU0_SB_DQ<16>
  VSS54  = GND
  DQ17_B  = M_C_CPU0_SB_DQ<17>
  VSS55  = GND
  DQS2_B_T  = M_C_CPU0_SB_DQS_DP<2>
  DQS2_B_C  = M_C_CPU0_SB_DQS_DN<2>
  VSS56  = GND
  DQ20_B  = M_C_CPU0_SB_DQ<20>
  VSS57  = GND
  DQ21_B  = M_C_CPU0_SB_DQ<21>
  VSS58  = GND
  DQ24_B  = M_C_CPU0_SB_DQ<24>
  VSS59  = GND
  DQ25_B  = M_C_CPU0_SB_DQ<25>
  VSS60  = GND
  DQS3_B_T  = M_C_CPU0_SB_DQS_DP<3>
  DQS3_B_C  = M_C_CPU0_SB_DQS_DN<3>
  VSS61  = GND
  DQ28_B  = M_C_CPU0_SB_DQ<28>
  VSS62  = GND
  DQ29_B  = M_C_CPU0_SB_DQ<29>
  VSS63  = GND
  RFU1  = TP_CHC_CPU0_DIMM2_FRU_1
  VIN_BULK1  = P12V_S3_AUX_CPU0_NVDIMM
  VIN_BULK2  = P12V_S3_AUX_CPU0_NVDIMM
  \pwr_good||fail_n\  = PWRGD_CHC_CPU0_DIMM2
  HSA  = PD_CHC_CPU0_DIMM2_SAA
  RFU2  = TP_CHC_CPU0_DIMM2_FRU_2
  RFU3  = TP_CHC_CPU0_DIMM2_FRU_3
  VSS64  = GND
  DQ2_A  = M_C_CPU0_SA_DQ<2>
  VSS65  = GND
  DQ3_A  = M_C_CPU0_SA_DQ<3>
  VSS66  = GND
  \dqs5_a_c||tdqs5_a_c||dqs5_a_t||tdqs5_a_t\  = M_C_CPU0_SA_DQS_DN<5>
  \dqs5_a_t||tdqs5_a_t\  = M_C_CPU0_SA_DQS_DP<5>
  VSS67  = GND
  DQ6_A  = M_C_CPU0_SA_DQ<6>
  VSS68  = GND
  DQ7_A  = M_C_CPU0_SA_DQ<7>
  VSS69  = GND
  DQ10_A  = M_C_CPU0_SA_DQ<10>
  VSS70  = GND
  DQ11_A  = M_C_CPU0_SA_DQ<11>
  VSS71  = GND
  \dqs6_a_c||tdqs6_a_c||dqs6_a_t||tdqs6_a_t\  = M_C_CPU0_SA_DQS_DN<6>
  \dqs6_a_t||tdqs6_a_t\  = M_C_CPU0_SA_DQS_DP<6>
  VSS72  = GND
  DQ14_A  = M_C_CPU0_SA_DQ<14>
  VSS73  = GND
  DQ15_A  = M_C_CPU0_SA_DQ<15>
  VSS74  = GND
  DQ18_A  = M_C_CPU0_SA_DQ<18>
  VSS75  = GND
  DQ19_A  = M_C_CPU0_SA_DQ<19>
  VSS76  = GND
  \dqs7_a_c||tdqs7_a_c\  = M_C_CPU0_SA_DQS_DN<7>
  \dqs7_a_t||tdqs7_a_t\  = M_C_CPU0_SA_DQS_DP<7>
  VSS77  = GND
  DQ22_A  = M_C_CPU0_SA_DQ<22>
  VSS78  = GND
  DQ23_A  = M_C_CPU0_SA_DQ<23>
  VSS79  = GND
  DQ26_A  = M_C_CPU0_SA_DQ<26>
  VSS80  = GND
  DQ27_A  = M_C_CPU0_SA_DQ<27>
  VSS81  = GND
  \dqs8_a_c||tdqs8_a_c\  = M_C_CPU0_SA_DQS_DN<8>
  \dqs8_a_t||tdqs8_a_t\  = M_C_CPU0_SA_DQS_DP<8>
  VSS82  = GND
  DQ30_A  = M_C_CPU0_SA_DQ<30>
  VSS83  = GND
  DQ31_A  = M_C_CPU0_SA_DQ<31>
  VSS84  = GND
  CB2_A  = M_C_CPU0_SA_CB<2>
  VSS85  = GND
  CB3_A  = M_C_CPU0_SA_CB<3>
  VSS86  = GND
  \dqs9_a_c||tdqs9_a_c\  = M_C_CPU0_SA_DQS_DN<9>
  \dqs9_a_t||tdqs9_a_t\  = M_C_CPU0_SA_DQS_DP<9>
  VSS87  = GND
  CB6_A  = M_C_CPU0_SA_CB<6>
  VSS88  = GND
  CB7_A  = M_C_CPU0_SA_CB<7>
  VSS89  = GND
  RESET_N  = RST_M_CD_CPU0_FPGA_N
  VSS90  = GND
  CS1_A_N  = M_C_CPU0_SA_CS_N<3>
  VSS91  = GND
  CA1_A  = M_C_CPU0_SA_CA<1>
  VSS92  = GND
  CA3_A  = M_C_CPU0_SA_CA<3>
  VSS93  = GND
  CA5_A  = M_C_CPU0_SA_CA<5>
  VSS94  = GND
  CK_T  = M_C_CPU0_CLK_DP<1>
  CK_C  = M_C_CPU0_CLK_DN<1>
  VSS95  = GND
  RFU4  = TP_CHC_CPU0_DIMM2_FRU_4
  CA1_B  = M_C_CPU0_SB_CA<1>
  VSS96  = GND
  CA3_B  = M_C_CPU0_SB_CA<3>
  VSS97  = GND
  CA5_B  = M_C_CPU0_SB_CA<5>
  VSS98  = GND
  PAR_B  = M_C_CPU0_SB_PAR
  VSS99  = GND
  CS1_B_N  = M_C_CPU0_SB_CS_N<3>
  VSS100  = GND
  RFU5  = TP_CHC_CPU0_DIMM2_FRU_5
  RFU6  = TP_CHC_CPU0_DIMM2_FRU_6
  VSS101  = GND
  CB6_B  = M_C_CPU0_SB_CB<6>
  VSS102  = GND
  CB7_B  = M_C_CPU0_SB_CB<7>
  VSS103  = GND
  DQS4_B_C  = M_C_CPU0_SB_DQS_DN<4>
  DQS4_B_T  = M_C_CPU0_SB_DQS_DP<4>
  VSS104  = GND
  CB2_B  = M_C_CPU0_SB_CB<2>
  VSS105  = GND
  CB3_B  = M_C_CPU0_SB_CB<3>
  VSS106  = GND
  DQ2_B  = M_C_CPU0_SB_DQ<2>
  VSS107  = GND
  DQ3_B  = M_C_CPU0_SB_DQ<3>
  VSS108  = GND
  \dqs5_b_c||tdqs5_b_c\  = M_C_CPU0_SB_DQS_DN<5>
  \dqs5_b_t||tdqs5_b_t\  = M_C_CPU0_SB_DQS_DP<5>
  VSS109  = GND
  DQ6_B  = M_C_CPU0_SB_DQ<6>
  VSS110  = GND
  DQ7_B  = M_C_CPU0_SB_DQ<7>
  VSS111  = GND
  DQ10_B  = M_C_CPU0_SB_DQ<10>
  VSS112  = GND
  DQ11_B  = M_C_CPU0_SB_DQ<11>
  VSS113  = GND
  \dqs6_b_c||tdqs6_b_c\  = M_C_CPU0_SB_DQS_DN<6>
  \dqs6_b_t||tdqs6_b_t\  = M_C_CPU0_SB_DQS_DP<6>
  VSS114  = GND
  DQ14_B  = M_C_CPU0_SB_DQ<14>
  VSS115  = GND
  DQ15_B  = M_C_CPU0_SB_DQ<15>
  VSS116  = GND
  DQ18_B  = M_C_CPU0_SB_DQ<18>
  VSS117  = GND
  DQ19_B  = M_C_CPU0_SB_DQ<19>
  VSS118  = GND
  \dqs7_b_c||tdqs7_b_c\  = M_C_CPU0_SB_DQS_DN<7>
  \dqs7_b_t||tdqs7_b_t\  = M_C_CPU0_SB_DQS_DP<7>
  VSS119  = GND
  DQ22_B  = M_C_CPU0_SB_DQ<22>
  VSS120  = GND
  DQ23_B  = M_C_CPU0_SB_DQ<23>
  VSS121  = GND
  DQ26_B  = M_C_CPU0_SB_DQ<26>
  VSS122  = GND
  DQ27_B  = M_C_CPU0_SB_DQ<27>
  VSS123  = GND
  \dqs8_b_c||tdqs8_b_c\  = M_C_CPU0_SB_DQS_DN<8>
  \dqs8_b_t||tdqs8_b_t\  = M_C_CPU0_SB_DQS_DP<8>
  VSS124  = GND
  DQ30_B  = M_C_CPU0_SB_DQ<30>
  VSS125  = GND
  DQ31_B  = M_C_CPU0_SB_DQ<31>
  VSS126  = GND
  G1  = GND
  G2  = GND
  G3  = GND

(kicad_pcb
	(version 20260206)
	(generator "pcbnew")
	(generator_version "10.0")
	(general
		(thickness 1.6)
		(legacy_teardrops no)
	)
	(paper "A4")
	(title_block
		(title "03242023_DA0F0TMBIJ0_F0T_Motherboard_J_brd_V01_OCP.brd")
		(comment 1 "Grand Teton / footprint 3553 of 6105 (J6), pads 46-91 of 291")
	)
	(layers
		(0 "F.Cu" signal "TOP")
		(4 "In1.Cu" signal "GND")
		(6 "In2.Cu" signal "IN1")
		(8 "In3.Cu" signal "GND1")
		(10 "In4.Cu" signal "IN2")
		(12 "In5.Cu" signal "GND2")
		(14 "In6.Cu" signal "IN3")
		(16 "In7.Cu" signal "GND3")
		(18 "In8.Cu" signal "VCC")
		(20 "In9.Cu" signal "VCC1")
		(22 "In10.Cu" signal "GND4")
		(24 "In11.Cu" signal "IN4")
		(26 "In12.Cu" signal "GND5")
		(28 "In13.Cu" signal "IN5")
		(30 "In14.Cu" signal "GND6")
		(32 "In15.Cu" signal "IN6")
		(34 "In16.Cu" signal "GND7")
		(2 "B.Cu" signal "BOTTOM")
		(9 "F.Adhes" user "F.Adhesive")
		(11 "B.Adhes" user "B.Adhesive")
		(13 "F.Paste" user "Package Geometry/Pastemask Top")
		(15 "B.Paste" user "Package Geometry/Pastemask Bottom")
		(5 "F.SilkS" user "Ref Des/Silkscreen Top")
		(7 "B.SilkS" user "Ref Des/Silkscreen Bottom")
		(1 "F.Mask" user "Board Geometry/Soldermask Top")
		(3 "B.Mask" user "Board Geometry/Soldermask Bottom")
		(17 "Dwgs.User" user "User.Drawings")
		(19 "Cmts.User" user "User.Comments")
		(21 "Eco1.User" user "User.Eco1")
		(23 "Eco2.User" user "User.Eco2")
		(25 "Edge.Cuts" user "Board Geometry/Outline")
		(27 "Margin" user)
		(31 "F.CrtYd" user "Package Geometry/Place Bound Top")
		(29 "B.CrtYd" user "Package Geometry/Place Bound Bottom")
		(35 "F.Fab" user "Ref Des/Assembly Top")
		(33 "B.Fab" user "Ref Des/Assembly Bottom")
	)
	(footprint ""
		(layer "F.Cu")
		(at 280.761948 -258.091686)
		(property "Reference" "J6"
			(at -3.683 -81.702148 0)
			(unlocked yes)
			(layer "F.SilkS")
			(effects
				(font
					(size 0.7874 0.5842)
					(thickness 0.1524)
				)
				(justify left)
			)
		)
		(property "Value" ""
			(at 0 0 0)
			(layer "F.Fab")
			(effects
				(font
					(size 1.27 1.27)
				)
			)
		)
		(duplicate_pad_numbers_are_jumpers no)
		(pad "46" smd rect
			(at -2.050034 -25.07488 270)
			(size 0.519938 1.4986)
			(layers "F.Cu" "F.Mask" "F.Paste")
			(net "GND")
		)
		(pad "47" smd rect
			(at -2.050034 -24.224996 270)
			(size 0.519938 1.4986)
			(layers "F.Cu" "F.Mask" "F.Paste")
			(net "M_C_CPU0_SA_DQ<28>")
		)
		(pad "48" smd rect
			(at -2.050034 -23.375112 270)
			(size 0.519938 1.4986)
			(layers "F.Cu" "F.Mask" "F.Paste")
			(net "GND")
		)
		(pad "49" smd rect
			(at -2.050034 -22.524974 270)
			(size 0.519938 1.4986)
			(layers "F.Cu" "F.Mask" "F.Paste")
			(net "M_C_CPU0_SA_DQ<29>")
		)
		(pad "50" smd rect
			(at -2.050034 -21.67509 270)
			(size 0.519938 1.4986)
			(layers "F.Cu" "F.Mask" "F.Paste")
			(net "GND")
		)
		(pad "51" smd rect
			(at -2.050034 -20.824952 270)
			(size 0.519938 1.4986)
			(layers "F.Cu" "F.Mask" "F.Paste")
			(net "M_C_CPU0_SA_CB<0>")
		)
		(pad "52" smd rect
			(at -2.050034 -19.975068 270)
			(size 0.519938 1.4986)
			(layers "F.Cu" "F.Mask" "F.Paste")
			(net "GND")
		)
		(pad "53" smd rect
			(at -2.050034 -19.12493 270)
			(size 0.519938 1.4986)
			(layers "F.Cu" "F.Mask" "F.Paste")
			(net "M_C_CPU0_SA_CB<1>")
		)
		(pad "54" smd rect
			(at -2.050034 -18.275046 270)
			(size 0.519938 1.4986)
			(layers "F.Cu" "F.Mask" "F.Paste")
			(net "GND")
		)
		(pad "55" smd rect
			(at -2.050034 -17.424908 270)
			(size 0.519938 1.4986)
			(layers "F.Cu" "F.Mask" "F.Paste")
			(net "M_C_CPU0_SA_DQS_DP<4>")
		)
		(pad "56" smd rect
			(at -2.050034 -16.575024 270)
			(size 0.519938 1.4986)
			(layers "F.Cu" "F.Mask" "F.Paste")
			(net "M_C_CPU0_SA_DQS_DN<4>")
		)
		(pad "57" smd rect
			(at -2.050034 -15.724886 270)
			(size 0.519938 1.4986)
			(layers "F.Cu" "F.Mask" "F.Paste")
			(net "GND")
		)
		(pad "58" smd rect
			(at -2.050034 -14.875002 270)
			(size 0.519938 1.4986)
			(layers "F.Cu" "F.Mask" "F.Paste")
			(net "M_C_CPU0_SA_CB<4>")
		)
		(pad "59" smd rect
			(at -2.050034 -14.025118 270)
			(size 0.519938 1.4986)
			(layers "F.Cu" "F.Mask" "F.Paste")
			(net "GND")
		)
		(pad "60" smd rect
			(at -2.050034 -13.17498 270)
			(size 0.519938 1.4986)
			(layers "F.Cu" "F.Mask" "F.Paste")
			(net "M_C_CPU0_SA_CB<5>")
		)
		(pad "61" smd rect
			(at -2.050034 -12.325096 270)
			(size 0.519938 1.4986)
			(layers "F.Cu" "F.Mask" "F.Paste")
			(net "GND")
		)
		(pad "62" smd rect
			(at -2.050034 -11.474958 270)
			(size 0.519938 1.4986)
			(layers "F.Cu" "F.Mask" "F.Paste")
			(net "M_C_CPU0_ALERT_N")
		)
		(pad "63" smd rect
			(at -2.050034 -10.625074 270)
			(size 0.519938 1.4986)
			(layers "F.Cu" "F.Mask" "F.Paste")
			(net "GND")
		)
		(pad "64" smd rect
			(at -2.050034 -9.774936 270)
			(size 0.519938 1.4986)
			(layers "F.Cu" "F.Mask" "F.Paste")
			(net "M_C_CPU0_SA_CS_N<2>")
		)
		(pad "65" smd rect
			(at -2.050034 -8.925052 270)
			(size 0.519938 1.4986)
			(layers "F.Cu" "F.Mask" "F.Paste")
			(net "GND")
		)
		(pad "66" smd rect
			(at -2.050034 -8.074914 270)
			(size 0.519938 1.4986)
			(layers "F.Cu" "F.Mask" "F.Paste")
			(net "M_C_CPU0_SA_CA<0>")
		)
		(pad "67" smd rect
			(at -2.050034 -7.22503 270)
			(size 0.519938 1.4986)
			(layers "F.Cu" "F.Mask" "F.Paste")
			(net "GND")
		)
		(pad "68" smd rect
			(at -2.050034 -6.374892 270)
			(size 0.519938 1.4986)
			(layers "F.Cu" "F.Mask" "F.Paste")
			(net "M_C_CPU0_SA_CA<2>")
		)
		(pad "69" smd rect
			(at -2.050034 -5.525008 270)
			(size 0.519938 1.4986)
			(layers "F.Cu" "F.Mask" "F.Paste")
			(net "GND")
		)
		(pad "70" smd rect
			(at -2.050034 -4.675124 270)
			(size 0.519938 1.4986)
			(layers "F.Cu" "F.Mask" "F.Paste")
			(net "M_C_CPU0_SA_CA<4>")
		)
		(pad "71" smd rect
			(at -2.050034 -3.824986 270)
			(size 0.519938 1.4986)
			(layers "F.Cu" "F.Mask" "F.Paste")
			(net "GND")
		)
		(pad "72" smd rect
			(at -2.050034 -2.975102 270)
			(size 0.519938 1.4986)
			(layers "F.Cu" "F.Mask" "F.Paste")
			(net "M_C_CPU0_SA_CA<6>")
		)
		(pad "73" smd rect
			(at -2.050034 -2.124964 270)
			(size 0.519938 1.4986)
			(layers "F.Cu" "F.Mask" "F.Paste")
			(net "GND")
		)
		(pad "74" smd rect
			(at -2.050034 -1.27508 270)
			(size 0.519938 1.4986)
			(layers "F.Cu" "F.Mask" "F.Paste")
			(net "M_C_CPU0_SA_PAR")
		)
		(pad "75" smd rect
			(at -2.050034 -0.424942 270)
			(size 0.519938 1.4986)
			(layers "F.Cu" "F.Mask" "F.Paste")
			(net "GND")
		)
		(pad "76" smd rect
			(at -2.050034 5.525008 270)
			(size 0.519938 1.4986)
			(layers "F.Cu" "F.Mask" "F.Paste")
			(net "M_C_CPU0_SB_CA<0>")
		)
		(pad "77" smd rect
			(at -2.050034 6.374892 270)
			(size 0.519938 1.4986)
			(layers "F.Cu" "F.Mask" "F.Paste")
			(net "GND")
		)
		(pad "78" smd rect
			(at -2.050034 7.22503 270)
			(size 0.519938 1.4986)
			(layers "F.Cu" "F.Mask" "F.Paste")
			(net "M_C_CPU0_SB_CA<2>")
		)
		(pad "79" smd rect
			(at -2.050034 8.074914 270)
			(size 0.519938 1.4986)
			(layers "F.Cu" "F.Mask" "F.Paste")
			(net "GND")
		)
		(pad "80" smd rect
			(at -2.050034 8.925052 270)
			(size 0.519938 1.4986)
			(layers "F.Cu" "F.Mask" "F.Paste")
			(net "M_C_CPU0_SB_CA<4>")
		)
		(pad "81" smd rect
			(at -2.050034 9.774936 270)
			(size 0.519938 1.4986)
			(layers "F.Cu" "F.Mask" "F.Paste")
			(net "GND")
		)
		(pad "82" smd rect
			(at -2.050034 10.625074 270)
			(size 0.519938 1.4986)
			(layers "F.Cu" "F.Mask" "F.Paste")
			(net "M_C_CPU0_SB_CA<6>")
		)
		(pad "83" smd rect
			(at -2.050034 11.474958 270)
			(size 0.519938 1.4986)
			(layers "F.Cu" "F.Mask" "F.Paste")
			(net "GND")
		)
		(pad "84" smd rect
			(at -2.050034 12.325096 270)
			(size 0.519938 1.4986)
			(layers "F.Cu" "F.Mask" "F.Paste")
			(net "M_C_CPU0_SB_CS_N<2>")
		)
		(pad "85" smd rect
			(at -2.050034 13.17498 270)
			(size 0.519938 1.4986)
			(layers "F.Cu" "F.Mask" "F.Paste")
			(net "GND")
		)
		(pad "86" smd rect
			(at -2.050034 14.025118 270)
			(size 0.519938 1.4986)
			(layers "F.Cu" "F.Mask" "F.Paste")
			(net "M_C_CPU0_SA_RSP<1>")
		)
		(pad "87" smd rect
			(at -2.050034 14.875002 270)
			(size 0.519938 1.4986)
			(layers "F.Cu" "F.Mask" "F.Paste")
			(net "M_C_CPU0_SB_RSP<1>")
		)
		(pad "88" smd rect
			(at -2.050034 15.724886 270)
			(size 0.519938 1.4986)
			(layers "F.Cu" "F.Mask" "F.Paste")
			(net "GND")
		)
		(pad "89" smd rect
			(at -2.050034 16.575024 270)
			(size 0.519938 1.4986)
			(layers "F.Cu" "F.Mask" "F.Paste")
			(net "M_C_CPU0_SB_CB<4>")
		)
		(pad "90" smd rect
			(at -2.050034 17.424908 270)
			(size 0.519938 1.4986)
			(layers "F.Cu" "F.Mask" "F.Paste")
			(net "GND")
		)
		(pad "91" smd rect
			(at -2.050034 18.275046 270)
			(size 0.519938 1.4986)
			(layers "F.Cu" "F.Mask" "F.Paste")
			(net "M_C_CPU0_SB_CB<5>")
		)
	)
)
